# S9S_MB_2U (Grand Teton) — schematic netlist excerpt (pin names and nets, part order shuffled) for the footprints in the layout excerpt that follows; sources: Cadence DE-HDL packaged netlist, KiCad conversion of 03242023_DA0F0TMBIJ0_F0T_Motherboard_J_brd_V01_OCP.brd

PC2146  Q_CAP  1UF 25V 10% EMPTY  pkg C0402  page 162 : A = GND ; B = P12V_OCP_REG_2
R3270  Q_RES  1K 1% EMPTY  pkg 0402LF  page 166 : A = FM_P2E_FGB ; B = GND

(kicad_pcb
	(version 20260206)
	(generator "pcbnew")
	(generator_version "10.0")
	(general
		(thickness 1.6)
		(legacy_teardrops no)
	)
	(paper "A4")
	(title_block
		(title "03242023_DA0F0TMBIJ0_F0T_Motherboard_J_brd_V01_OCP.brd")
		(comment 1 "Grand Teton / footprints 289-290 of 6105")
	)
	(layers
		(0 "F.Cu" signal "TOP")
		(4 "In1.Cu" signal "GND")
		(6 "In2.Cu" signal "IN1")
		(8 "In3.Cu" signal "GND1")
		(10 "In4.Cu" signal "IN2")
		(12 "In5.Cu" signal "GND2")
		(14 "In6.Cu" signal "IN3")
		(16 "In7.Cu" signal "GND3")
		(18 "In8.Cu" signal "VCC")
		(20 "In9.Cu" signal "VCC1")
		(22 "In10.Cu" signal "GND4")
		(24 "In11.Cu" signal "IN4")
		(26 "In12.Cu" signal "GND5")
		(28 "In13.Cu" signal "IN5")
		(30 "In14.Cu" signal "GND6")
		(32 "In15.Cu" signal "IN6")
		(34 "In16.Cu" signal "GND7")
		(2 "B.Cu" signal "BOTTOM")
		(9 "F.Adhes" user "F.Adhesive")
		(11 "B.Adhes" user "B.Adhesive")
		(13 "F.Paste" user "Package Geometry/Pastemask Top")
		(15 "B.Paste" user "Package Geometry/Pastemask Bottom")
		(5 "F.SilkS" user "Ref Des/Silkscreen Top")
		(7 "B.SilkS" user "Ref Des/Silkscreen Bottom")
		(1 "F.Mask" user "Board Geometry/Soldermask Top")
		(3 "B.Mask" user "Board Geometry/Soldermask Bottom")
		(17 "Dwgs.User" user "User.Drawings")
		(19 "Cmts.User" user "User.Comments")
		(21 "Eco1.User" user "User.Eco1")
		(23 "Eco2.User" user "User.Eco2")
		(25 "Edge.Cuts" user "Board Geometry/Outline")
		(27 "Margin" user)
		(31 "F.CrtYd" user "Package Geometry/Place Bound Top")
		(29 "B.CrtYd" user "Package Geometry/Place Bound Bottom")
		(35 "F.Fab" user "Ref Des/Assembly Top")
		(33 "B.Fab" user "Ref Des/Assembly Bottom")
	)
	(footprint ""
		(layer "F.Cu")
		(at 27.628596 -393.342876)
		(property "Reference" "R3270"
			(at 0 0 0)
			(layer "F.SilkS")
			(hide yes)
			(effects
				(font
					(size 1.27 1.27)
				)
			)
		)
		(property "Value" ""
			(at 0 0 0)
			(layer "F.Fab")
			(effects
				(font
					(size 1.27 1.27)
				)
			)
		)
		(duplicate_pad_numbers_are_jumpers no)
		(fp_line
			(start -0.7874 -0.4064)
			(end 0.7874 -0.4064)
			(stroke
				(width 0.1524)
				(type default)
			)
			(layer "F.SilkS")
		)
		(fp_line
			(start -0.7874 0.4064)
			(end -0.7874 -0.4064)
			(stroke
				(width 0.1524)
				(type default)
			)
			(layer "F.SilkS")
		)
		(fp_line
			(start 0.7874 -0.4064)
			(end 0.7874 0.4064)
			(stroke
				(width 0.1524)
				(type default)
			)
			(layer "F.SilkS")
		)
		(fp_line
			(start 0.7874 0.4064)
			(end -0.7874 0.4064)
			(stroke
				(width 0.1524)
				(type default)
			)
			(layer "F.SilkS")
		)
		(fp_line
			(start -0.67945 -0.305054)
			(end -0.12065 -0.305054)
			(stroke
				(width 0.1)
				(type default)
			)
			(layer "F.Fab")
		)
		(fp_line
			(start -0.67945 0.3048)
			(end -0.67945 -0.305054)
			(stroke
				(width 0.1)
				(type default)
			)
			(layer "F.Fab")
		)
		(fp_line
			(start -0.12065 -0.305054)
			(end -0.12065 -0.2794)
			(stroke
				(width 0.1)
				(type default)
			)
			(layer "F.Fab")
		)
		(fp_line
			(start -0.12065 -0.2794)
			(end 0.12065 -0.2794)
			(stroke
				(width 0.1)
				(type default)
			)
			(layer "F.Fab")
		)
		(fp_line
			(start -0.12065 0.2794)
			(end -0.12065 0.3048)
			(stroke
				(width 0.1)
				(type default)
			)
			(layer "F.Fab")
		)
		(fp_line
			(start -0.12065 0.3048)
			(end -0.67945 0.3048)
			(stroke
				(width 0.1)
				(type default)
			)
			(layer "F.Fab")
		)
		(fp_line
			(start 0.120396 0.2794)
			(end -0.12065 0.2794)
			(stroke
				(width 0.1)
				(type default)
			)
			(layer "F.Fab")
		)
		(fp_line
			(start 0.120396 0.3048)
			(end 0.120396 0.2794)
			(stroke
				(width 0.1)
				(type default)
			)
			(layer "F.Fab")
		)
		(fp_line
			(start 0.12065 -0.3048)
			(end 0.67945 -0.3048)
			(stroke
				(width 0.1)
				(type default)
			)
			(layer "F.Fab")
		)
		(fp_line
			(start 0.12065 -0.2794)
			(end 0.12065 -0.3048)
			(stroke
				(width 0.1)
				(type default)
			)
			(layer "F.Fab")
		)
		(fp_line
			(start 0.67945 -0.3048)
			(end 0.67945 0.3048)
			(stroke
				(width 0.1)
				(type default)
			)
			(layer "F.Fab")
		)
		(fp_line
			(start 0.67945 0.3048)
			(end 0.120396 0.3048)
			(stroke
				(width 0.1)
				(type default)
			)
			(layer "F.Fab")
		)
		(pad "1" smd circle
			(at -0.40005 0)
			(size 0 0)
			(layers "F.Cu" "F.Mask" "F.Paste")
			(net "FM_P2E_FGB")
		)
		(pad "2" smd circle
			(at 0.40005 0)
			(size 0 0)
			(layers "F.Cu" "F.Mask" "F.Paste")
			(net "GND")
		)
	)
	(footprint ""
		(layer "F.Cu")
		(at 75.424538 -19.220942)
		(property "Reference" "PC2146"
			(at 0 0 0)
			(layer "F.SilkS")
			(hide yes)
			(effects
				(font
					(size 1.27 1.27)
				)
			)
		)
		(property "Value" ""
			(at 0 0 0)
			(layer "F.Fab")
			(effects
				(font
					(size 1.27 1.27)
				)
			)
		)
		(duplicate_pad_numbers_are_jumpers no)
		(fp_line
			(start -0.7874 -0.4064)
			(end 0.7874 -0.4064)
			(stroke
				(width 0.1524)
				(type default)
			)
			(layer "F.SilkS")
		)
		(fp_line
			(start -0.7874 0.4064)
			(end -0.7874 -0.4064)
			(stroke
				(width 0.1524)
				(type default)
			)
			(layer "F.SilkS")
		)
		(fp_line
			(start 0.7874 -0.4064)
			(end 0.7874 0.4064)
			(stroke
				(width 0.1524)
				(type default)
			)
			(layer "F.SilkS")
		)
		(fp_line
			(start 0.7874 0.4064)
			(end -0.7874 0.4064)
			(stroke
				(width 0.1524)
				(type default)
			)
			(layer "F.SilkS")
		)
		(fp_line
			(start -0.67945 -0.305054)
			(end -0.12065 -0.305054)
			(stroke
				(width 0.1)
				(type default)
			)
			(layer "F.Fab")
		)
		(fp_line
			(start -0.67945 0.3048)
			(end -0.67945 -0.305054)
			(stroke
				(width 0.1)
				(type default)
			)
			(layer "F.Fab")
		)
		(fp_line
			(start -0.12065 -0.305054)
			(end -0.12065 -0.2794)
			(stroke
				(width 0.1)
				(type default)
			)
			(layer "F.Fab")
		)
		(fp_line
			(start -0.12065 -0.2794)
			(end 0.12065 -0.2794)
			(stroke
				(width 0.1)
				(type default)
			)
			(layer "F.Fab")
		)
		(fp_line
			(start -0.12065 0.2794)
			(end -0.12065 0.3048)
			(stroke
				(width 0.1)
				(type default)
			)
			(layer "F.Fab")
		)
		(fp_line
			(start -0.12065 0.3048)
			(end -0.67945 0.3048)
			(stroke
				(width 0.1)
				(type default)
			)
			(layer "F.Fab")
		)
		(fp_line
			(start 0.120396 0.2794)
			(end -0.12065 0.2794)
			(stroke
				(width 0.1)
				(type default)
			)
			(layer "F.Fab")
		)
		(fp_line
			(start 0.120396 0.3048)
			(end 0.120396 0.2794)
			(stroke
				(width 0.1)
				(type default)
			)
			(layer "F.Fab")
		)
		(fp_line
			(start 0.12065 -0.3048)
			(end 0.67945 -0.3048)
			(stroke
				(width 0.1)
				(type default)
			)
			(layer "F.Fab")
		)
		(fp_line
			(start 0.12065 -0.2794)
			(end 0.12065 -0.3048)
			(stroke
				(width 0.1)
				(type default)
			)
			(layer "F.Fab")
		)
		(fp_line
			(start 0.67945 -0.3048)
			(end 0.67945 0.3048)
			(stroke
				(width 0.1)
				(type default)
			)
			(layer "F.Fab")
		)
		(fp_line
			(start 0.67945 0.3048)
			(end 0.120396 0.3048)
			(stroke
				(width 0.1)
				(type default)
			)
			(layer "F.Fab")
		)
		(pad "1" smd circle
			(at -0.40005 0)
			(size 0 0)
			(layers "F.Cu" "F.Mask" "F.Paste")
			(net "GND")
		)
		(pad "2" smd circle
			(at 0.40005 0)
			(size 0 0)
			(layers "F.Cu" "F.Mask" "F.Paste")
			(net "P12V_OCP_REG_2")
		)
	)
)
